# T6G (Grand Teton) — schematic netlist excerpt (pin names and nets, part order shuffled) for the footprints in the layout excerpt that follows; sources: Cadence DE-HDL packaged netlist, KiCad conversion of 04192023_DAF0TMB3IC0_F0TG_MB_C_brd_V02_OCP.brd

Q6001  METR3904G  METR3904-G IC  pkg SOT23_BEC  page 267
  \1\  = P12V_HSC_TEMP_R
  \3\  = P12V_HSC_TEMP_R
  \2\  = P12V_HSC_TEMP_E

C1275  Q_CAP  0.1UF 25V 10% X7R  pkg 0402  page 133 : A = P3V3_AUX ; B = GND

(kicad_pcb
	(version 20260206)
	(generator "pcbnew")
	(generator_version "10.0")
	(general
		(thickness 1.6)
		(legacy_teardrops no)
	)
	(paper "A4")
	(title_block
		(title "04192023_DAF0TMB3IC0_F0TG_MB_C_brd_V02_OCP.brd")
		(comment 1 "Grand Teton / footprints 2192-2193 of 8354")
	)
	(layers
		(0 "F.Cu" signal "TOP")
		(4 "In1.Cu" signal "GND")
		(6 "In2.Cu" signal "IN1")
		(8 "In3.Cu" signal "GND1")
		(10 "In4.Cu" signal "IN2")
		(12 "In5.Cu" signal "GND2")
		(14 "In6.Cu" signal "IN3")
		(16 "In7.Cu" signal "GND3")
		(18 "In8.Cu" signal "VCC")
		(20 "In9.Cu" signal "VCC1")
		(22 "In10.Cu" signal "GND4")
		(24 "In11.Cu" signal "IN4")
		(26 "In12.Cu" signal "GND5")
		(28 "In13.Cu" signal "IN5")
		(30 "In14.Cu" signal "GND6")
		(32 "In15.Cu" signal "IN6")
		(34 "In16.Cu" signal "GND7")
		(2 "B.Cu" signal "BOTTOM")
		(9 "F.Adhes" user "F.Adhesive")
		(11 "B.Adhes" user "B.Adhesive")
		(13 "F.Paste" user "Package Geometry/Pastemask Top")
		(15 "B.Paste" user "Package Geometry/Pastemask Bottom")
		(5 "F.SilkS" user "Ref Des/Silkscreen Top")
		(7 "B.SilkS" user "Ref Des/Silkscreen Bottom")
		(1 "F.Mask" user "Board Geometry/Soldermask Top")
		(3 "B.Mask" user "Board Geometry/Soldermask Bottom")
		(17 "Dwgs.User" user "User.Drawings")
		(19 "Cmts.User" user "User.Comments")
		(21 "Eco1.User" user "User.Eco1")
		(23 "Eco2.User" user "User.Eco2")
		(25 "Edge.Cuts" user "Board Geometry/Outline")
		(27 "Margin" user)
		(31 "F.CrtYd" user "Package Geometry/Place Bound Top")
		(29 "B.CrtYd" user "Package Geometry/Place Bound Bottom")
		(35 "F.Fab" user "Ref Des/Assembly Top")
		(33 "B.Fab" user "Ref Des/Assembly Bottom")
	)
	(footprint ""
		(layer "F.Cu")
		(at 211.572348 -14.892528)
		(property "Reference" "C1275"
			(at 0 0 0)
			(layer "F.SilkS")
			(hide yes)
			(effects
				(font
					(size 1.27 1.27)
				)
			)
		)
		(property "Value" ""
			(at 0 0 0)
			(layer "F.Fab")
			(effects
				(font
					(size 1.27 1.27)
				)
			)
		)
		(duplicate_pad_numbers_are_jumpers no)
		(fp_line
			(start -0.7874 -0.4064)
			(end 0.7874 -0.4064)
			(stroke
				(width 0.1524)
				(type default)
			)
			(layer "F.SilkS")
		)
		(fp_line
			(start -0.7874 0.4064)
			(end -0.7874 -0.4064)
			(stroke
				(width 0.1524)
				(type default)
			)
			(layer "F.SilkS")
		)
		(fp_line
			(start 0.7874 -0.4064)
			(end 0.7874 0.4064)
			(stroke
				(width 0.1524)
				(type default)
			)
			(layer "F.SilkS")
		)
		(fp_line
			(start 0.7874 0.4064)
			(end -0.7874 0.4064)
			(stroke
				(width 0.1524)
				(type default)
			)
			(layer "F.SilkS")
		)
		(fp_line
			(start -0.67945 -0.305054)
			(end -0.12065 -0.305054)
			(stroke
				(width 0.1)
				(type default)
			)
			(layer "F.Fab")
		)
		(fp_line
			(start -0.67945 0.3048)
			(end -0.67945 -0.305054)
			(stroke
				(width 0.1)
				(type default)
			)
			(layer "F.Fab")
		)
		(fp_line
			(start -0.12065 -0.305054)
			(end -0.12065 -0.2794)
			(stroke
				(width 0.1)
				(type default)
			)
			(layer "F.Fab")
		)
		(fp_line
			(start -0.12065 -0.2794)
			(end 0.12065 -0.2794)
			(stroke
				(width 0.1)
				(type default)
			)
			(layer "F.Fab")
		)
		(fp_line
			(start -0.12065 0.2794)
			(end -0.12065 0.3048)
			(stroke
				(width 0.1)
				(type default)
			)
			(layer "F.Fab")
		)
		(fp_line
			(start -0.12065 0.3048)
			(end -0.67945 0.3048)
			(stroke
				(width 0.1)
				(type default)
			)
			(layer "F.Fab")
		)
		(fp_line
			(start 0.120396 0.2794)
			(end -0.12065 0.2794)
			(stroke
				(width 0.1)
				(type default)
			)
			(layer "F.Fab")
		)
		(fp_line
			(start 0.120396 0.3048)
			(end 0.120396 0.2794)
			(stroke
				(width 0.1)
				(type default)
			)
			(layer "F.Fab")
		)
		(fp_line
			(start 0.12065 -0.3048)
			(end 0.67945 -0.3048)
			(stroke
				(width 0.1)
				(type default)
			)
			(layer "F.Fab")
		)
		(fp_line
			(start 0.12065 -0.2794)
			(end 0.12065 -0.3048)
			(stroke
				(width 0.1)
				(type default)
			)
			(layer "F.Fab")
		)
		(fp_line
			(start 0.67945 -0.3048)
			(end 0.67945 0.3048)
			(stroke
				(width 0.1)
				(type default)
			)
			(layer "F.Fab")
		)
		(fp_line
			(start 0.67945 0.3048)
			(end 0.120396 0.3048)
			(stroke
				(width 0.1)
				(type default)
			)
			(layer "F.Fab")
		)
		(pad "1" smd circle
			(at -0.40005 0)
			(size 0 0)
			(layers "F.Cu" "F.Mask" "F.Paste")
			(net "P3V3_AUX")
		)
		(pad "2" smd circle
			(at 0.40005 0)
			(size 0 0)
			(layers "F.Cu" "F.Mask" "F.Paste")
			(net "GND")
		)
	)
	(footprint ""
		(layer "F.Cu")
		(at 286.0675 -409.277058 -90)
		(property "Reference" "Q6001"
			(at 1.861566 -2.29997 90)
			(unlocked yes)
			(layer "F.SilkS")
			(effects
				(font
					(size 0.7874 0.5842)
					(thickness 0.1524)
				)
				(justify left)
			)
		)
		(property "Value" ""
			(at 0 0 270)
			(layer "F.Fab")
			(effects
				(font
					(size 1.27 1.27)
				)
			)
		)
		(duplicate_pad_numbers_are_jumpers no)
		(fp_line
			(start -1.905 1.651)
			(end -1.905 -1.651)
			(stroke
				(width 0.1524)
				(type default)
			)
			(layer "F.SilkS")
		)
		(fp_line
			(start 1.905 1.651)
			(end -1.905 1.651)
			(stroke
				(width 0.1524)
				(type default)
			)
			(layer "F.SilkS")
		)
		(fp_line
			(start -1.905 -1.651)
			(end 1.905 -1.651)
			(stroke
				(width 0.1524)
				(type default)
			)
			(layer "F.SilkS")
		)
		(fp_line
			(start 1.905 -1.651)
			(end 1.905 1.651)
			(stroke
				(width 0.1524)
				(type default)
			)
			(layer "F.SilkS")
		)
		(fp_line
			(start -0.649986 1.524)
			(end -0.649986 1.169924)
			(stroke
				(width 0.1)
				(type default)
			)
			(layer "F.Fab")
		)
		(fp_line
			(start 0.6985 1.524)
			(end -0.649986 1.524)
			(stroke
				(width 0.1)
				(type default)
			)
			(layer "F.Fab")
		)
		(fp_line
			(start -1.249934 1.169924)
			(end -1.249934 0.729996)
			(stroke
				(width 0.1)
				(type default)
			)
			(layer "F.Fab")
		)
		(fp_line
			(start -0.649986 1.169924)
			(end -1.249934 1.169924)
			(stroke
				(width 0.1)
				(type default)
			)
			(layer "F.Fab")
		)
		(fp_line
			(start -1.249934 0.729996)
			(end -0.6985 0.729996)
			(stroke
				(width 0.1)
				(type default)
			)
			(layer "F.Fab")
		)
		(fp_line
			(start -0.6985 0.729996)
			(end -0.6985 -0.729996)
			(stroke
				(width 0.1)
				(type default)
			)
			(layer "F.Fab")
		)
		(fp_line
			(start 0.6985 0.219964)
			(end 0.6985 1.524)
			(stroke
				(width 0.1)
				(type default)
			)
			(layer "F.Fab")
		)
		(fp_line
			(start 1.249934 0.219964)
			(end 0.6985 0.219964)
			(stroke
				(width 0.1)
				(type default)
			)
			(layer "F.Fab")
		)
		(fp_line
			(start 0.6985 -0.219964)
			(end 1.249934 -0.219964)
			(stroke
				(width 0.1)
				(type default)
			)
			(layer "F.Fab")
		)
		(fp_line
			(start 1.249934 -0.219964)
			(end 1.249934 0.219964)
			(stroke
				(width 0.1)
				(type default)
			)
			(layer "F.Fab")
		)
		(fp_line
			(start -1.249934 -0.729996)
			(end -1.249934 -1.169924)
			(stroke
				(width 0.1)
				(type default)
			)
			(layer "F.Fab")
		)
		(fp_line
			(start -0.6985 -0.729996)
			(end -1.249934 -0.729996)
			(stroke
				(width 0.1)
				(type default)
			)
			(layer "F.Fab")
		)
		(fp_line
			(start -1.249934 -1.169924)
			(end -0.649986 -1.169924)
			(stroke
				(width 0.1)
				(type default)
			)
			(layer "F.Fab")
		)
		(fp_line
			(start -0.649986 -1.169924)
			(end -0.649986 -1.524)
			(stroke
				(width 0.1)
				(type default)
			)
			(layer "F.Fab")
		)
		(fp_line
			(start -0.649986 -1.524)
			(end 0.6985 -1.524)
			(stroke
				(width 0.1)
				(type default)
			)
			(layer "F.Fab")
		)
		(fp_line
			(start 0.6985 -1.524)
			(end 0.6985 -0.219964)
			(stroke
				(width 0.1)
				(type default)
			)
			(layer "F.Fab")
		)
		(pad "B" smd rect
			(at -1.1176 -1.016 180)
			(size 1.016 1.27)
			(layers "F.Cu" "F.Mask" "F.Paste")
			(net "P12V_HSC_TEMP_R")
		)
		(pad "C" smd rect
			(at 1.1176 0 180)
			(size 1.016 1.27)
			(layers "F.Cu" "F.Mask" "F.Paste")
			(net "P12V_HSC_TEMP_R")
		)
		(pad "E" smd rect
			(at -1.1176 1.016 180)
			(size 1.016 1.27)
			(layers "F.Cu" "F.Mask" "F.Paste")
			(net "P12V_HSC_TEMP_E")
		)
	)
)
